(kicad_pcb
	(version 20260206)
	(generator "pcbnew")
	(generator_version "10.0")
	(general
		(thickness 1.6)
		(legacy_teardrops no)
	)
	(paper "A4")
	(title_block
		(title "01162023_DA0F0TEBIF0_F0T_Expander_BD_F_brd_V02_OCP.brd")
		(comment 1 "Grand Teton / footprints 6543-6549 of 9728")
	)
	(layers
		(0 "F.Cu" signal "TOP")
		(4 "In1.Cu" signal "GND")
		(6 "In2.Cu" signal "VCC")
		(8 "In3.Cu" signal "VCC1")
		(10 "In4.Cu" signal "GND1")
		(12 "In5.Cu" signal "IN1")
		(14 "In6.Cu" signal "GND2")
		(16 "In7.Cu" signal "IN2")
		(18 "In8.Cu" signal "GND3")
		(20 "In9.Cu" signal "IN3")
		(22 "In10.Cu" signal "GND4")
		(24 "In11.Cu" signal "IN4")
		(26 "In12.Cu" signal "GND5")
		(28 "In13.Cu" signal "IN5")
		(30 "In14.Cu" signal "GND6")
		(32 "In15.Cu" signal "IN6")
		(34 "In16.Cu" signal "GND7")
		(2 "B.Cu" signal "BOTTOM")
		(9 "F.Adhes" user "F.Adhesive")
		(11 "B.Adhes" user "B.Adhesive")
		(13 "F.Paste" user "Package Geometry/Pastemask Top")
		(15 "B.Paste" user "Package Geometry/Pastemask Bottom")
		(5 "F.SilkS" user "Ref Des/Silkscreen Top")
		(7 "B.SilkS" user "Ref Des/Silkscreen Bottom")
		(1 "F.Mask" user "Board Geometry/Soldermask Top")
		(3 "B.Mask" user "Board Geometry/Soldermask Bottom")
		(17 "Dwgs.User" user "User.Drawings")
		(19 "Cmts.User" user "User.Comments")
		(21 "Eco1.User" user "User.Eco1")
		(23 "Eco2.User" user "User.Eco2")
		(25 "Edge.Cuts" user "Board Geometry/Outline")
		(27 "Margin" user)
		(31 "F.CrtYd" user "Package Geometry/Place Bound Top")
		(29 "B.CrtYd" user "Package Geometry/Place Bound Bottom")
		(35 "F.Fab" user "Ref Des/Assembly Top")
		(33 "B.Fab" user "Ref Des/Assembly Bottom")
	)
	(footprint ""
		(layer "F.Cu")
		(at 130.490468 -356.244906 90)
		(property "Reference" "C2255"
			(at 0 0 90)
			(layer "F.SilkS")
			(hide yes)
			(effects
				(font
					(size 1.27 1.27)
				)
			)
		)
		(property "Value" ""
			(at 0 0 90)
			(layer "F.Fab")
			(effects
				(font
					(size 1.27 1.27)
				)
			)
		)
		(duplicate_pad_numbers_are_jumpers no)
		(fp_line
			(start 0.299974 -0.150114)
			(end 0.299974 0.150114)
			(stroke
				(width 0.1)
				(type default)
			)
			(layer "F.Fab")
		)
		(fp_line
			(start -0.299974 -0.150114)
			(end 0.299974 -0.150114)
			(stroke
				(width 0.1)
				(type default)
			)
			(layer "F.Fab")
		)
		(fp_line
			(start 0.299974 0.150114)
			(end -0.299974 0.150114)
			(stroke
				(width 0.1)
				(type default)
			)
			(layer "F.Fab")
		)
		(fp_line
			(start -0.299974 0.150114)
			(end -0.299974 -0.150114)
			(stroke
				(width 0.1)
				(type default)
			)
			(layer "F.Fab")
		)
		(pad "1" smd rect
			(at -0.2667 0 90)
			(size 0.3048 0.381)
			(layers "F.Cu" "F.Mask" "F.Paste")
			(net "P5E_PEX1_STN5_TX_DP<89>")
		)
		(pad "2" smd rect
			(at 0.2667 0 90)
			(size 0.3048 0.381)
			(layers "F.Cu" "F.Mask" "F.Paste")
			(net "P5E_PEX1_STN5_TX_C_DP<89>")
		)
	)
	(footprint ""
		(layer "F.Cu")
		(at 315.954156 -48.21809)
		(property "Reference" "PD75"
			(at -3.432556 2.29616 0)
			(unlocked yes)
			(layer "F.SilkS")
			(effects
				(font
					(size 0.7874 0.5842)
					(thickness 0.1524)
				)
				(justify left)
			)
		)
		(property "Value" ""
			(at 0 0 0)
			(layer "F.Fab")
			(effects
				(font
					(size 1.27 1.27)
				)
			)
		)
		(duplicate_pad_numbers_are_jumpers no)
		(fp_line
			(start -3.400044 -1.459992)
			(end 4.107942 -1.459992)
			(stroke
				(width 0.1524)
				(type default)
			)
			(layer "F.SilkS")
		)
		(fp_line
			(start -3.400044 1.459992)
			(end -3.400044 -1.459992)
			(stroke
				(width 0.1524)
				(type default)
			)
			(layer "F.SilkS")
		)
		(fp_line
			(start 4.107942 -1.459992)
			(end 4.107942 1.459992)
			(stroke
				(width 0.1524)
				(type default)
			)
			(layer "F.SilkS")
		)
		(fp_line
			(start 4.107942 1.459992)
			(end -3.400044 1.459992)
			(stroke
				(width 0.1524)
				(type default)
			)
			(layer "F.SilkS")
		)
		(fp_poly
			(pts
				(xy 4.107942 -1.459992) (xy 4.107942 1.459992) (xy 3.308096 1.459992) (xy 3.308096 -1.459992)
			)
			(stroke
				(width 0)
				(type default)
			)
			(fill yes)
			(layer "F.SilkS")
		)
		(fp_line
			(start -2.29997 -1.459992)
			(end 2.29997 -1.459992)
			(stroke
				(width 0.1)
				(type default)
			)
			(layer "F.Fab")
		)
		(fp_line
			(start -2.29997 1.459992)
			(end -2.29997 -1.459992)
			(stroke
				(width 0.1)
				(type default)
			)
			(layer "F.Fab")
		)
		(fp_line
			(start 2.29997 -1.459992)
			(end 2.29997 1.459992)
			(stroke
				(width 0.1)
				(type default)
			)
			(layer "F.Fab")
		)
		(fp_line
			(start 2.29997 1.459992)
			(end -2.29997 1.459992)
			(stroke
				(width 0.1)
				(type default)
			)
			(layer "F.Fab")
		)
		(fp_text user "+"
			(at -4.7752 -0.12065 0)
			(unlocked yes)
			(layer "F.SilkS")
			(effects
				(font
					(size 1.905 1.4224)
					(thickness 0.1524)
				)
				(justify left)
			)
		)
		(fp_text user "-"
			(at 5.4102 0.29845 180)
			(unlocked yes)
			(layer "F.SilkS")
			(effects
				(font
					(size 1.905 1.4224)
					(thickness 0.1524)
				)
				(justify left)
			)
		)
		(fp_text user "+"
			(at -4.7752 -0.12065 0)
			(unlocked yes)
			(layer "F.Fab")
			(effects
				(font
					(size 1.905 1.4224)
					(thickness 0.1524)
				)
				(justify left)
			)
		)
		(fp_text user "-"
			(at 5.4102 0.29845 180)
			(unlocked yes)
			(layer "F.Fab")
			(effects
				(font
					(size 1.905 1.4224)
					(thickness 0.1524)
				)
				(justify left)
			)
		)
		(pad "A" smd rect
			(at -1.999996 0 90)
			(size 1.7018 2.5146)
			(layers "F.Cu" "F.Mask" "F.Paste")
			(net "GND")
		)
		(pad "C" smd rect
			(at 1.999996 0 90)
			(size 1.7018 2.5146)
			(layers "F.Cu" "F.Mask" "F.Paste")
			(net "P3V3_SSD11")
		)
	)
	(footprint ""
		(layer "F.Cu")
		(at 202.220576 -26.666444 -90)
		(property "Reference" "R4067"
			(at 0 0 270)
			(layer "F.SilkS")
			(hide yes)
			(effects
				(font
					(size 1.27 1.27)
				)
			)
		)
		(property "Value" ""
			(at 0 0 270)
			(layer "F.Fab")
			(effects
				(font
					(size 1.27 1.27)
				)
			)
		)
		(duplicate_pad_numbers_are_jumpers no)
		(fp_line
			(start -0.7874 0.4064)
			(end -0.7874 -0.4064)
			(stroke
				(width 0.1524)
				(type default)
			)
			(layer "F.SilkS")
		)
		(fp_line
			(start 0.7874 0.4064)
			(end -0.7874 0.4064)
			(stroke
				(width 0.1524)
				(type default)
			)
			(layer "F.SilkS")
		)
		(fp_line
			(start -0.7874 -0.4064)
			(end 0.7874 -0.4064)
			(stroke
				(width 0.1524)
				(type default)
			)
			(layer "F.SilkS")
		)
		(fp_line
			(start 0.7874 -0.4064)
			(end 0.7874 0.4064)
			(stroke
				(width 0.1524)
				(type default)
			)
			(layer "F.SilkS")
		)
		(fp_line
			(start -0.67945 0.3048)
			(end -0.67945 -0.305054)
			(stroke
				(width 0.1)
				(type default)
			)
			(layer "F.Fab")
		)
		(fp_line
			(start -0.12065 0.3048)
			(end -0.67945 0.3048)
			(stroke
				(width 0.1)
				(type default)
			)
			(layer "F.Fab")
		)
		(fp_line
			(start 0.120396 0.3048)
			(end 0.120396 0.2794)
			(stroke
				(width 0.1)
				(type default)
			)
			(layer "F.Fab")
		)
		(fp_line
			(start 0.67945 0.3048)
			(end 0.120396 0.3048)
			(stroke
				(width 0.1)
				(type default)
			)
			(layer "F.Fab")
		)
		(fp_line
			(start -0.12065 0.2794)
			(end -0.12065 0.3048)
			(stroke
				(width 0.1)
				(type default)
			)
			(layer "F.Fab")
		)
		(fp_line
			(start 0.120396 0.2794)
			(end -0.12065 0.2794)
			(stroke
				(width 0.1)
				(type default)
			)
			(layer "F.Fab")
		)
		(fp_line
			(start -0.12065 -0.2794)
			(end 0.12065 -0.2794)
			(stroke
				(width 0.1)
				(type default)
			)
			(layer "F.Fab")
		)
		(fp_line
			(start 0.12065 -0.2794)
			(end 0.12065 -0.3048)
			(stroke
				(width 0.1)
				(type default)
			)
			(layer "F.Fab")
		)
		(fp_line
			(start 0.12065 -0.3048)
			(end 0.67945 -0.3048)
			(stroke
				(width 0.1)
				(type default)
			)
			(layer "F.Fab")
		)
		(fp_line
			(start 0.67945 -0.3048)
			(end 0.67945 0.3048)
			(stroke
				(width 0.1)
				(type default)
			)
			(layer "F.Fab")
		)
		(fp_line
			(start -0.67945 -0.305054)
			(end -0.12065 -0.305054)
			(stroke
				(width 0.1)
				(type default)
			)
			(layer "F.Fab")
		)
		(fp_line
			(start -0.12065 -0.305054)
			(end -0.12065 -0.2794)
			(stroke
				(width 0.1)
				(type default)
			)
			(layer "F.Fab")
		)
		(pad "1" smd circle
			(at -0.40005 0 270)
			(size 0 0)
			(layers "F.Cu" "F.Mask" "F.Paste")
			(net "PRSNT_SSD7_R_N")
		)
		(pad "2" smd circle
			(at 0.40005 0 270)
			(size 0 0)
			(layers "F.Cu" "F.Mask" "F.Paste")
			(net "PRSNT_SSD7_N")
		)
	)
	(footprint ""
		(layer "F.Cu")
		(at 411.97784 -117.566186)
		(property "Reference" "R398"
			(at 0 0 0)
			(layer "F.SilkS")
			(hide yes)
			(effects
				(font
					(size 1.27 1.27)
				)
			)
		)
		(property "Value" ""
			(at 0 0 0)
			(layer "F.Fab")
			(effects
				(font
					(size 1.27 1.27)
				)
			)
		)
		(duplicate_pad_numbers_are_jumpers no)
		(fp_line
			(start -0.7874 -0.4064)
			(end 0.7874 -0.4064)
			(stroke
				(width 0.1524)
				(type default)
			)
			(layer "F.SilkS")
		)
		(fp_line
			(start -0.7874 0.4064)
			(end -0.7874 -0.4064)
			(stroke
				(width 0.1524)
				(type default)
			)
			(layer "F.SilkS")
		)
		(fp_line
			(start 0.7874 -0.4064)
			(end 0.7874 0.4064)
			(stroke
				(width 0.1524)
				(type default)
			)
			(layer "F.SilkS")
		)
		(fp_line
			(start 0.7874 0.4064)
			(end -0.7874 0.4064)
			(stroke
				(width 0.1524)
				(type default)
			)
			(layer "F.SilkS")
		)
		(fp_line
			(start -0.67945 -0.305054)
			(end -0.12065 -0.305054)
			(stroke
				(width 0.1)
				(type default)
			)
			(layer "F.Fab")
		)
		(fp_line
			(start -0.67945 0.3048)
			(end -0.67945 -0.305054)
			(stroke
				(width 0.1)
				(type default)
			)
			(layer "F.Fab")
		)
		(fp_line
			(start -0.12065 -0.305054)
			(end -0.12065 -0.2794)
			(stroke
				(width 0.1)
				(type default)
			)
			(layer "F.Fab")
		)
		(fp_line
			(start -0.12065 -0.2794)
			(end 0.12065 -0.2794)
			(stroke
				(width 0.1)
				(type default)
			)
			(layer "F.Fab")
		)
		(fp_line
			(start -0.12065 0.2794)
			(end -0.12065 0.3048)
			(stroke
				(width 0.1)
				(type default)
			)
			(layer "F.Fab")
		)
		(fp_line
			(start -0.12065 0.3048)
			(end -0.67945 0.3048)
			(stroke
				(width 0.1)
				(type default)
			)
			(layer "F.Fab")
		)
		(fp_line
			(start 0.120396 0.2794)
			(end -0.12065 0.2794)
			(stroke
				(width 0.1)
				(type default)
			)
			(layer "F.Fab")
		)
		(fp_line
			(start 0.120396 0.3048)
			(end 0.120396 0.2794)
			(stroke
				(width 0.1)
				(type default)
			)
			(layer "F.Fab")
		)
		(fp_line
			(start 0.12065 -0.3048)
			(end 0.67945 -0.3048)
			(stroke
				(width 0.1)
				(type default)
			)
			(layer "F.Fab")
		)
		(fp_line
			(start 0.12065 -0.2794)
			(end 0.12065 -0.3048)
			(stroke
				(width 0.1)
				(type default)
			)
			(layer "F.Fab")
		)
		(fp_line
			(start 0.67945 -0.3048)
			(end 0.67945 0.3048)
			(stroke
				(width 0.1)
				(type default)
			)
			(layer "F.Fab")
		)
		(fp_line
			(start 0.67945 0.3048)
			(end 0.120396 0.3048)
			(stroke
				(width 0.1)
				(type default)
			)
			(layer "F.Fab")
		)
		(pad "1" smd circle
			(at -0.40005 0)
			(size 0 0)
			(layers "F.Cu" "F.Mask" "F.Paste")
			(net "PRSNT_NIC7_N")
		)
		(pad "2" smd circle
			(at 0.40005 0)
			(size 0 0)
			(layers "F.Cu" "F.Mask" "F.Paste")
			(net "PRSNTB2_NIC7_N")
		)
	)
	(footprint ""
		(layer "F.Cu")
		(at 334.628998 -293.816786 -90)
		(property "Reference" "PC147"
			(at 0 0 270)
			(layer "F.SilkS")
			(hide yes)
			(effects
				(font
					(size 1.27 1.27)
				)
			)
		)
		(property "Value" ""
			(at 0 0 270)
			(layer "F.Fab")
			(effects
				(font
					(size 1.27 1.27)
				)
			)
		)
		(duplicate_pad_numbers_are_jumpers no)
		(fp_line
			(start -0.7874 0.4064)
			(end -0.7874 -0.4064)
			(stroke
				(width 0.1524)
				(type default)
			)
			(layer "F.SilkS")
		)
		(fp_line
			(start 0.7874 0.4064)
			(end -0.7874 0.4064)
			(stroke
				(width 0.1524)
				(type default)
			)
			(layer "F.SilkS")
		)
		(fp_line
			(start -0.7874 -0.4064)
			(end 0.7874 -0.4064)
			(stroke
				(width 0.1524)
				(type default)
			)
			(layer "F.SilkS")
		)
		(fp_line
			(start 0.7874 -0.4064)
			(end 0.7874 0.4064)
			(stroke
				(width 0.1524)
				(type default)
			)
			(layer "F.SilkS")
		)
		(fp_line
			(start -0.67945 0.3048)
			(end -0.67945 -0.305054)
			(stroke
				(width 0.1)
				(type default)
			)
			(layer "F.Fab")
		)
		(fp_line
			(start -0.12065 0.3048)
			(end -0.67945 0.3048)
			(stroke
				(width 0.1)
				(type default)
			)
			(layer "F.Fab")
		)
		(fp_line
			(start 0.120396 0.3048)
			(end 0.120396 0.2794)
			(stroke
				(width 0.1)
				(type default)
			)
			(layer "F.Fab")
		)
		(fp_line
			(start 0.67945 0.3048)
			(end 0.120396 0.3048)
			(stroke
				(width 0.1)
				(type default)
			)
			(layer "F.Fab")
		)
		(fp_line
			(start -0.12065 0.2794)
			(end -0.12065 0.3048)
			(stroke
				(width 0.1)
				(type default)
			)
			(layer "F.Fab")
		)
		(fp_line
			(start 0.120396 0.2794)
			(end -0.12065 0.2794)
			(stroke
				(width 0.1)
				(type default)
			)
			(layer "F.Fab")
		)
		(fp_line
			(start -0.12065 -0.2794)
			(end 0.12065 -0.2794)
			(stroke
				(width 0.1)
				(type default)
			)
			(layer "F.Fab")
		)
		(fp_line
			(start 0.12065 -0.2794)
			(end 0.12065 -0.3048)
			(stroke
				(width 0.1)
				(type default)
			)
			(layer "F.Fab")
		)
		(fp_line
			(start 0.12065 -0.3048)
			(end 0.67945 -0.3048)
			(stroke
				(width 0.1)
				(type default)
			)
			(layer "F.Fab")
		)
		(fp_line
			(start 0.67945 -0.3048)
			(end 0.67945 0.3048)
			(stroke
				(width 0.1)
				(type default)
			)
			(layer "F.Fab")
		)
		(fp_line
			(start -0.67945 -0.305054)
			(end -0.12065 -0.305054)
			(stroke
				(width 0.1)
				(type default)
			)
			(layer "F.Fab")
		)
		(fp_line
			(start -0.12065 -0.305054)
			(end -0.12065 -0.2794)
			(stroke
				(width 0.1)
				(type default)
			)
			(layer "F.Fab")
		)
		(pad "1" smd circle
			(at -0.40005 0 270)
			(size 0 0)
			(layers "F.Cu" "F.Mask" "F.Paste")
			(net "P0V8_PEX2")
		)
		(pad "2" smd circle
			(at 0.40005 0 270)
			(size 0 0)
			(layers "F.Cu" "F.Mask" "F.Paste")
			(net "GND")
		)
	)
	(footprint ""
		(layer "F.Cu")
		(at 52.267866 -56.353456)
		(property "Reference" "C2863"
			(at 0 0 0)
			(layer "F.SilkS")
			(hide yes)
			(effects
				(font
					(size 1.27 1.27)
				)
			)
		)
		(property "Value" ""
			(at 0 0 0)
			(layer "F.Fab")
			(effects
				(font
					(size 1.27 1.27)
				)
			)
		)
		(duplicate_pad_numbers_are_jumpers no)
		(fp_line
			(start -0.7874 -0.4064)
			(end 0.7874 -0.4064)
			(stroke
				(width 0.1524)
				(type default)
			)
			(layer "F.SilkS")
		)
		(fp_line
			(start -0.7874 0.4064)
			(end -0.7874 -0.4064)
			(stroke
				(width 0.1524)
				(type default)
			)
			(layer "F.SilkS")
		)
		(fp_line
			(start 0.7874 -0.4064)
			(end 0.7874 0.4064)
			(stroke
				(width 0.1524)
				(type default)
			)
			(layer "F.SilkS")
		)
		(fp_line
			(start 0.7874 0.4064)
			(end -0.7874 0.4064)
			(stroke
				(width 0.1524)
				(type default)
			)
			(layer "F.SilkS")
		)
		(fp_line
			(start -0.67945 -0.305054)
			(end -0.12065 -0.305054)
			(stroke
				(width 0.1)
				(type default)
			)
			(layer "F.Fab")
		)
		(fp_line
			(start -0.67945 0.3048)
			(end -0.67945 -0.305054)
			(stroke
				(width 0.1)
				(type default)
			)
			(layer "F.Fab")
		)
		(fp_line
			(start -0.12065 -0.305054)
			(end -0.12065 -0.2794)
			(stroke
				(width 0.1)
				(type default)
			)
			(layer "F.Fab")
		)
		(fp_line
			(start -0.12065 -0.2794)
			(end 0.12065 -0.2794)
			(stroke
				(width 0.1)
				(type default)
			)
			(layer "F.Fab")
		)
		(fp_line
			(start -0.12065 0.2794)
			(end -0.12065 0.3048)
			(stroke
				(width 0.1)
				(type default)
			)
			(layer "F.Fab")
		)
		(fp_line
			(start -0.12065 0.3048)
			(end -0.67945 0.3048)
			(stroke
				(width 0.1)
				(type default)
			)
			(layer "F.Fab")
		)
		(fp_line
			(start 0.120396 0.2794)
			(end -0.12065 0.2794)
			(stroke
				(width 0.1)
				(type default)
			)
			(layer "F.Fab")
		)
		(fp_line
			(start 0.120396 0.3048)
			(end 0.120396 0.2794)
			(stroke
				(width 0.1)
				(type default)
			)
			(layer "F.Fab")
		)
		(fp_line
			(start 0.12065 -0.3048)
			(end 0.67945 -0.3048)
			(stroke
				(width 0.1)
				(type default)
			)
			(layer "F.Fab")
		)
		(fp_line
			(start 0.12065 -0.2794)
			(end 0.12065 -0.3048)
			(stroke
				(width 0.1)
				(type default)
			)
			(layer "F.Fab")
		)
		(fp_line
			(start 0.67945 -0.3048)
			(end 0.67945 0.3048)
			(stroke
				(width 0.1)
				(type default)
			)
			(layer "F.Fab")
		)
		(fp_line
			(start 0.67945 0.3048)
			(end 0.120396 0.3048)
			(stroke
				(width 0.1)
				(type default)
			)
			(layer "F.Fab")
		)
		(pad "1" smd circle
			(at -0.40005 0)
			(size 0 0)
			(layers "F.Cu" "F.Mask" "F.Paste")
			(net "SSD1_PWR_EN_R")
		)
		(pad "2" smd circle
			(at 0.40005 0)
			(size 0 0)
			(layers "F.Cu" "F.Mask" "F.Paste")
			(net "GND")
		)
	)
	(footprint ""
		(layer "F.Cu")
		(at 383.59842 -343.952322 90)
		(property "Reference" "C772"
			(at 0 0 90)
			(layer "F.SilkS")
			(hide yes)
			(effects
				(font
					(size 1.27 1.27)
				)
			)
		)
		(property "Value" ""
			(at 0 0 90)
			(layer "F.Fab")
			(effects
				(font
					(size 1.27 1.27)
				)
			)
		)
		(duplicate_pad_numbers_are_jumpers no)
		(fp_line
			(start 0.299974 -0.150114)
			(end 0.299974 0.150114)
			(stroke
				(width 0.1)
				(type default)
			)
			(layer "F.Fab")
		)
		(fp_line
			(start -0.299974 -0.150114)
			(end 0.299974 -0.150114)
			(stroke
				(width 0.1)
				(type default)
			)
			(layer "F.Fab")
		)
		(fp_line
			(start 0.299974 0.150114)
			(end -0.299974 0.150114)
			(stroke
				(width 0.1)
				(type default)
			)
			(layer "F.Fab")
		)
		(fp_line
			(start -0.299974 0.150114)
			(end -0.299974 -0.150114)
			(stroke
				(width 0.1)
				(type default)
			)
			(layer "F.Fab")
		)
		(pad "1" smd rect
			(at -0.2667 0 90)
			(size 0.3048 0.381)
			(layers "F.Cu" "F.Mask" "F.Paste")
			(net "P5E_PEX3_STN6_TX_DP<106>")
		)
		(pad "2" smd rect
			(at 0.2667 0 90)
			(size 0.3048 0.381)
			(layers "F.Cu" "F.Mask" "F.Paste")
			(net "P5E_PEX3_STN6_TX_C_DP<106>")
		)
	)
)
